#ISCELL
  mstr_symbols design_note *
  *
#ISCELL
  mstr_symbols intel_corp_bpage *
  *
#CELL
  mstr_sconn sconn24_h46321001 *
  page91_i1
#ISCELL
  mstr_standard offpage *
  page91_i10
#ISCELL
  mstr_standard offpage *
  page91_i11
#ISCELL
  mstr_standard offpage *
  page91_i12
#CELL
  mstr_discrete res *
  page91_i14
#CELL
  mstr_discrete res *
  page91_i16
#CELL
  mstr_discrete res *
  page91_i17
#CELL
  mstr_discrete res *
  page91_i18
#ISCELL
  mstr_symbols gnd *
  page91_i2
#CELL
  mstr_discrete res *
  page91_i20
#CELL
  mstr_discrete res *
  page91_i21
#CELL
  mstr_discrete res *
  page91_i22
#CELL
  mstr_discrete res *
  page91_i24
#ISCELL
  mstr_standard offpage *
  page91_i25
#ISCELL
  mstr_standard offpage *
  page91_i26
#ISCELL
  mstr_standard offpage *
  page91_i27
#ISCELL
  mstr_standard offpage *
  page91_i28
#ISCELL
  mstr_standard offpage *
  page91_i29
#ISCELL
  mstr_standard offpage *
  page91_i3
#ISCELL
  mstr_symbols pvpp_abc *
  page91_i30
#ISCELL
  mstr_symbols pvpp_abc *
  page91_i31
#ISCELL
  mstr_symbols pvpp_abc *
  page91_i32
#ISCELL
  mstr_symbols p3v3 *
  page91_i33
#CELL
  mstr_discrete res *
  page91_i34
#CELL
  mstr_discrete res *
  page91_i35
#CELL
  mstr_discrete res *
  page91_i36
#CELL
  mstr_discrete res *
  page91_i37
#ISCELL
  mstr_symbols gnd *
  page91_i38
#ISCELL
  mstr_standard offpage *
  page91_i4
#ISCELL
  mstr_standard offpage *
  page91_i5
#ISCELL
  mstr_standard offpage *
  page91_i6
#ISCELL
  mstr_standard offpage *
  page91_i7
#ISCELL
  mstr_standard offpage *
  page91_i8
#ISCELL
  mstr_standard offpage *
  page91_i9
